#ISCELL
  mstr_misc dns *
  *
#ISCELL
  pure_quanta quanta_title_block_c *
  *
#ISCELL
  logical_power universal_gnd *
  page258_i1
#CELL
  pure_quanta isl99390frztr5935 *
  page258_i10
#CELL
  pure_quanta q_res *
  page258_i11
#ISCELL
  logical_power vcc15 *
  page258_i12
#CELL
  pure_quanta q_cap *
  page258_i13
#ISCELL
  logical_power universal_gnd *
  page258_i14
#CELL
  pure_quanta q_res *
  page258_i15
#ISCELL
  standard offpage *
  page258_i16
#ISCELL
  standard offpage *
  page258_i17
#CELL
  pure_quanta q_cap *
  page258_i18
#ISCELL
  logical_power universal_gnd *
  page258_i19
#ISCELL
  logical_power universal_gnd *
  page258_i2
#ISCELL
  logical_power universal_gnd *
  page258_i20
#ISCELL
  standard offpage *
  page258_i21
#ISCELL
  standard offpage *
  page258_i22
#CELL
  pure_quanta q_cap *
  page258_i23
#ISCELL
  logical_power universal_gnd *
  page258_i24
#CELL
  pure_quanta q_cap *
  page258_i25
#CELL
  pure_quanta q_res *
  page258_i26
#ISCELL
  logical_power vcc15 *
  page258_i27
#CELL
  pure_quanta q_cap *
  page258_i28
#ISCELL
  logical_power universal_gnd *
  page258_i29
#CELL
  pure_quanta q_res *
  page258_i3
#ISCELL
  logical_power universal_gnd *
  page258_i30
#CELL
  pure_quanta q_cap *
  page258_i31
#ISCELL
  logical_power universal_gnd *
  page258_i32
#CELL
  pure_quanta q_res *
  page258_i33
#CELL
  pure_quanta q_cap *
  page258_i34
#CELL
  pure_quanta q_cap *
  page258_i35
#CELL
  pure_quanta q_cap *
  page258_i36
#CELL
  pure_quanta q_cap *
  page258_i37
#CELL
  pure_quanta q_res *
  page258_i38
#CELL
  pure_quanta q_inductor *
  page258_i39
#ISCELL
  standard offpage *
  page258_i4
#CELL
  pure_quanta q_cap *
  page258_i40
#CELL
  pure_quanta q_cap *
  page258_i41
#ISCELL
  logical_power universal_gnd *
  page258_i42
#ISCELL
  logical_power vcc15 *
  page258_i43
#CELL
  pure_quanta q_cap *
  page258_i44
#CELL
  pure_quanta q_res *
  page258_i45
#CELL
  pure_quanta q_cap *
  page258_i46
#CELL
  pure_quanta q_cap *
  page258_i47
#CELL
  pure_quanta q_cap *
  page258_i48
#CELL
  pure_quanta q_cap *
  page258_i49
#ISCELL
  standard offpage *
  page258_i5
#CELL
  pure_quanta q_res *
  page258_i50
#CELL
  pure_quanta q_inductor *
  page258_i51
#ISCELL
  logical_power universal_gnd *
  page258_i52
#CELL
  pure_quanta q_cap *
  page258_i53
#ISCELL
  logical_power vcc15 *
  page258_i54
#CELL
  pure_quanta q_cap *
  page258_i55
#ISCELL
  logical_power gnd *
  page258_i56
#CELL
  pure_quanta q_cap *
  page258_i57
#ISCELL
  logical_power vcc15 *
  page258_i58
#CELL
  pure_quanta q_inductor *
  page258_i59
#ISCELL
  standard offpage *
  page258_i6
#CELL
  pure_quanta q_cap *
  page258_i60
#CELL
  pure_quanta q_cap *
  page258_i61
#ISCELL
  logical_power universal_gnd *
  page258_i62
#ISCELL
  logical_power vcc15 *
  page258_i63
#CELL
  pure_quanta q_capp *
  page258_i64
#CELL
  pure_quanta q_capp *
  page258_i65
#ISCELL
  logical_power universal_gnd *
  page258_i66
#ISCELL
  logical_power universal_gnd *
  page258_i67
#CELL
  pure_quanta q_capp *
  page258_i68
#CELL
  pure_quanta q_capp *
  page258_i69
#ISCELL
  standard offpage *
  page258_i7
#CELL
  pure_quanta q_capp *
  page258_i70
#ISCELL
  logical_power vcc15 *
  page258_i71
#CELL
  pure_quanta q_cap *
  page258_i72
#CELL
  pure_quanta q_cap *
  page258_i73
#ISCELL
  logical_power vcc15 *
  page258_i74
#CELL
  pure_quanta q_cap *
  page258_i75
#CELL
  pure_quanta q_cap *
  page258_i76
#CELL
  pure_quanta q_cap *
  page258_i77
#ISCELL
  logical_power universal_gnd *
  page258_i78
#CELL
  pure_quanta q_cap *
  page258_i79
#ISCELL
  logical_power universal_gnd *
  page258_i8
#CELL
  pure_quanta q_capp *
  page258_i80
#ISCELL
  logical_power vcc15 *
  page258_i81
#CELL
  pure_quanta isl99390frztr5935 *
  page258_i82
#CELL
  pure_quanta q_cap *
  page258_i9
